# T6G (Grand Teton) — schematic netlist excerpt (pin names and nets, part order shuffled) for the footprints in the layout excerpt that follows; sources: Cadence DE-HDL packaged netlist, KiCad conversion of 04192023_DAF0TMB3IC0_F0TG_MB_C_brd_V02_OCP.brd

R4202  Q_RES  1K 1% EMPTY  pkg 0402LF  page 235 : A = P3V3_AUX ; B = U272_2_ADD0
R657  Q_RES  0 5% CHIP  pkg 0402LF  page 364 : A = P0V9_RETIMER_CPU1_PMSCL ; B = P0V9_RETIMER_CPU1_PMSCL_R
C945  Q_CAP_DIFFBUS  DIFF BUS_0.22UF 6.3V 20% X6S  pkg C0201  page 63 : \1\ = P5E_CPU0_P1_TX_C_DP<10> ; \2\ = P5E_CPU0_P1_TX_DP<10>

(kicad_pcb
	(version 20260206)
	(generator "pcbnew")
	(generator_version "10.0")
	(general
		(thickness 1.6)
		(legacy_teardrops no)
	)
	(paper "A4")
	(title_block
		(title "04192023_DAF0TMB3IC0_F0TG_MB_C_brd_V02_OCP.brd")
		(comment 1 "Grand Teton / footprints 4194-4196 of 8354")
	)
	(layers
		(0 "F.Cu" signal "TOP")
		(4 "In1.Cu" signal "GND")
		(6 "In2.Cu" signal "IN1")
		(8 "In3.Cu" signal "GND1")
		(10 "In4.Cu" signal "IN2")
		(12 "In5.Cu" signal "GND2")
		(14 "In6.Cu" signal "IN3")
		(16 "In7.Cu" signal "GND3")
		(18 "In8.Cu" signal "VCC")
		(20 "In9.Cu" signal "VCC1")
		(22 "In10.Cu" signal "GND4")
		(24 "In11.Cu" signal "IN4")
		(26 "In12.Cu" signal "GND5")
		(28 "In13.Cu" signal "IN5")
		(30 "In14.Cu" signal "GND6")
		(32 "In15.Cu" signal "IN6")
		(34 "In16.Cu" signal "GND7")
		(2 "B.Cu" signal "BOTTOM")
		(9 "F.Adhes" user "F.Adhesive")
		(11 "B.Adhes" user "B.Adhesive")
		(13 "F.Paste" user "Package Geometry/Pastemask Top")
		(15 "B.Paste" user "Package Geometry/Pastemask Bottom")
		(5 "F.SilkS" user "Ref Des/Silkscreen Top")
		(7 "B.SilkS" user "Ref Des/Silkscreen Bottom")
		(1 "F.Mask" user "Board Geometry/Soldermask Top")
		(3 "B.Mask" user "Board Geometry/Soldermask Bottom")
		(17 "Dwgs.User" user "User.Drawings")
		(19 "Cmts.User" user "User.Comments")
		(21 "Eco1.User" user "User.Eco1")
		(23 "Eco2.User" user "User.Eco2")
		(25 "Edge.Cuts" user "Board Geometry/Outline")
		(27 "Margin" user)
		(31 "F.CrtYd" user "Package Geometry/Place Bound Top")
		(29 "B.CrtYd" user "Package Geometry/Place Bound Bottom")
		(35 "F.Fab" user "Ref Des/Assembly Top")
		(33 "B.Fab" user "Ref Des/Assembly Bottom")
	)
	(footprint ""
		(layer "F.Cu")
		(at 16.162782 -404.341584 90)
		(property "Reference" "R657"
			(at 0 0 90)
			(layer "F.SilkS")
			(hide yes)
			(effects
				(font
					(size 1.27 1.27)
				)
			)
		)
		(property "Value" ""
			(at 0 0 90)
			(layer "F.Fab")
			(effects
				(font
					(size 1.27 1.27)
				)
			)
		)
		(duplicate_pad_numbers_are_jumpers no)
		(fp_line
			(start 0.7874 -0.4064)
			(end 0.7874 0.4064)
			(stroke
				(width 0.1524)
				(type default)
			)
			(layer "F.SilkS")
		)
		(fp_line
			(start -0.7874 -0.4064)
			(end 0.7874 -0.4064)
			(stroke
				(width 0.1524)
				(type default)
			)
			(layer "F.SilkS")
		)
		(fp_line
			(start 0.7874 0.4064)
			(end -0.7874 0.4064)
			(stroke
				(width 0.1524)
				(type default)
			)
			(layer "F.SilkS")
		)
		(fp_line
			(start -0.7874 0.4064)
			(end -0.7874 -0.4064)
			(stroke
				(width 0.1524)
				(type default)
			)
			(layer "F.SilkS")
		)
		(fp_line
			(start -0.12065 -0.305054)
			(end -0.12065 -0.2794)
			(stroke
				(width 0.1)
				(type default)
			)
			(layer "F.Fab")
		)
		(fp_line
			(start -0.67945 -0.305054)
			(end -0.12065 -0.305054)
			(stroke
				(width 0.1)
				(type default)
			)
			(layer "F.Fab")
		)
		(fp_line
			(start 0.67945 -0.3048)
			(end 0.67945 0.3048)
			(stroke
				(width 0.1)
				(type default)
			)
			(layer "F.Fab")
		)
		(fp_line
			(start 0.12065 -0.3048)
			(end 0.67945 -0.3048)
			(stroke
				(width 0.1)
				(type default)
			)
			(layer "F.Fab")
		)
		(fp_line
			(start 0.12065 -0.2794)
			(end 0.12065 -0.3048)
			(stroke
				(width 0.1)
				(type default)
			)
			(layer "F.Fab")
		)
		(fp_line
			(start -0.12065 -0.2794)
			(end 0.12065 -0.2794)
			(stroke
				(width 0.1)
				(type default)
			)
			(layer "F.Fab")
		)
		(fp_line
			(start 0.120396 0.2794)
			(end -0.12065 0.2794)
			(stroke
				(width 0.1)
				(type default)
			)
			(layer "F.Fab")
		)
		(fp_line
			(start -0.12065 0.2794)
			(end -0.12065 0.3048)
			(stroke
				(width 0.1)
				(type default)
			)
			(layer "F.Fab")
		)
		(fp_line
			(start 0.67945 0.3048)
			(end 0.120396 0.3048)
			(stroke
				(width 0.1)
				(type default)
			)
			(layer "F.Fab")
		)
		(fp_line
			(start 0.120396 0.3048)
			(end 0.120396 0.2794)
			(stroke
				(width 0.1)
				(type default)
			)
			(layer "F.Fab")
		)
		(fp_line
			(start -0.12065 0.3048)
			(end -0.67945 0.3048)
			(stroke
				(width 0.1)
				(type default)
			)
			(layer "F.Fab")
		)
		(fp_line
			(start -0.67945 0.3048)
			(end -0.67945 -0.305054)
			(stroke
				(width 0.1)
				(type default)
			)
			(layer "F.Fab")
		)
		(pad "1" smd circle
			(at -0.40005 0 90)
			(size 0 0)
			(layers "F.Cu" "F.Mask" "F.Paste")
			(net "P0V9_RETIMER_CPU1_PMSCL")
		)
		(pad "2" smd circle
			(at 0.40005 0 90)
			(size 0 0)
			(layers "F.Cu" "F.Mask" "F.Paste")
			(net "P0V9_RETIMER_CPU1_PMSCL_R")
		)
	)
	(footprint ""
		(layer "F.Cu")
		(at 350.237044 -383.88163 -90)
		(property "Reference" "C945"
			(at 0 0 270)
			(layer "F.SilkS")
			(hide yes)
			(effects
				(font
					(size 1.27 1.27)
				)
			)
		)
		(property "Value" ""
			(at 0 0 270)
			(layer "F.Fab")
			(effects
				(font
					(size 1.27 1.27)
				)
			)
		)
		(duplicate_pad_numbers_are_jumpers no)
		(fp_line
			(start -0.299974 0.150114)
			(end -0.299974 -0.150114)
			(stroke
				(width 0.1)
				(type default)
			)
			(layer "F.Fab")
		)
		(fp_line
			(start 0.299974 0.150114)
			(end -0.299974 0.150114)
			(stroke
				(width 0.1)
				(type default)
			)
			(layer "F.Fab")
		)
		(fp_line
			(start -0.299974 -0.150114)
			(end 0.299974 -0.150114)
			(stroke
				(width 0.1)
				(type default)
			)
			(layer "F.Fab")
		)
		(fp_line
			(start 0.299974 -0.150114)
			(end 0.299974 0.150114)
			(stroke
				(width 0.1)
				(type default)
			)
			(layer "F.Fab")
		)
		(pad "1" smd rect
			(at -0.2667 0 270)
			(size 0.3048 0.381)
			(layers "F.Cu" "F.Mask" "F.Paste")
			(net "P5E_CPU0_P1_TX_C_DP<10>")
		)
		(pad "2" smd rect
			(at 0.2667 0 270)
			(size 0.3048 0.381)
			(layers "F.Cu" "F.Mask" "F.Paste")
			(net "P5E_CPU0_P1_TX_DP<10>")
		)
	)
	(footprint ""
		(layer "F.Cu")
		(at 98.380296 -425.82973 -90)
		(property "Reference" "R4202"
			(at 0 0 270)
			(layer "F.SilkS")
			(hide yes)
			(effects
				(font
					(size 1.27 1.27)
				)
			)
		)
		(property "Value" ""
			(at 0 0 270)
			(layer "F.Fab")
			(effects
				(font
					(size 1.27 1.27)
				)
			)
		)
		(duplicate_pad_numbers_are_jumpers no)
		(fp_line
			(start -0.7874 0.4064)
			(end -0.7874 -0.4064)
			(stroke
				(width 0.1524)
				(type default)
			)
			(layer "F.SilkS")
		)
		(fp_line
			(start 0.7874 0.4064)
			(end -0.7874 0.4064)
			(stroke
				(width 0.1524)
				(type default)
			)
			(layer "F.SilkS")
		)
		(fp_line
			(start -0.7874 -0.4064)
			(end 0.7874 -0.4064)
			(stroke
				(width 0.1524)
				(type default)
			)
			(layer "F.SilkS")
		)
		(fp_line
			(start 0.7874 -0.4064)
			(end 0.7874 0.4064)
			(stroke
				(width 0.1524)
				(type default)
			)
			(layer "F.SilkS")
		)
		(fp_line
			(start -0.67945 0.3048)
			(end -0.67945 -0.305054)
			(stroke
				(width 0.1)
				(type default)
			)
			(layer "F.Fab")
		)
		(fp_line
			(start -0.12065 0.3048)
			(end -0.67945 0.3048)
			(stroke
				(width 0.1)
				(type default)
			)
			(layer "F.Fab")
		)
		(fp_line
			(start 0.120396 0.3048)
			(end 0.120396 0.2794)
			(stroke
				(width 0.1)
				(type default)
			)
			(layer "F.Fab")
		)
		(fp_line
			(start 0.67945 0.3048)
			(end 0.120396 0.3048)
			(stroke
				(width 0.1)
				(type default)
			)
			(layer "F.Fab")
		)
		(fp_line
			(start -0.12065 0.2794)
			(end -0.12065 0.3048)
			(stroke
				(width 0.1)
				(type default)
			)
			(layer "F.Fab")
		)
		(fp_line
			(start 0.120396 0.2794)
			(end -0.12065 0.2794)
			(stroke
				(width 0.1)
				(type default)
			)
			(layer "F.Fab")
		)
		(fp_line
			(start -0.12065 -0.2794)
			(end 0.12065 -0.2794)
			(stroke
				(width 0.1)
				(type default)
			)
			(layer "F.Fab")
		)
		(fp_line
			(start 0.12065 -0.2794)
			(end 0.12065 -0.3048)
			(stroke
				(width 0.1)
				(type default)
			)
			(layer "F.Fab")
		)
		(fp_line
			(start 0.12065 -0.3048)
			(end 0.67945 -0.3048)
			(stroke
				(width 0.1)
				(type default)
			)
			(layer "F.Fab")
		)
		(fp_line
			(start 0.67945 -0.3048)
			(end 0.67945 0.3048)
			(stroke
				(width 0.1)
				(type default)
			)
			(layer "F.Fab")
		)
		(fp_line
			(start -0.67945 -0.305054)
			(end -0.12065 -0.305054)
			(stroke
				(width 0.1)
				(type default)
			)
			(layer "F.Fab")
		)
		(fp_line
			(start -0.12065 -0.305054)
			(end -0.12065 -0.2794)
			(stroke
				(width 0.1)
				(type default)
			)
			(layer "F.Fab")
		)
		(pad "1" smd circle
			(at -0.40005 0 270)
			(size 0 0)
			(layers "F.Cu" "F.Mask" "F.Paste")
			(net "P3V3_AUX")
		)
		(pad "2" smd circle
			(at 0.40005 0 270)
			(size 0 0)
			(layers "F.Cu" "F.Mask" "F.Paste")
			(net "U272_2_ADD0")
		)
	)
)
